# BASEBOARD_FAB2 (Tioga Pass) — schematic netlist excerpt (pin names and nets, part order shuffled) for the footprints in the layout excerpt that follows; sources: Cadence DE-HDL packaged netlist, KiCad conversion of Wiwynn_Tioga_Pass_MB.brd

EU7F1  NCP3232L  IC  pkg SM  page 231
  SS  = VR_PVPP_ABC_SS
  FB  = VR_FB_PVPP_ABC
  COMP  = VR_COMP_PVPP_ABC_3
  ISET  = VR_PVPP_ABC_ISET
  AGND  = AGND_PVPP_ABC
  OTS  = AGND_PVPP_ABC
  PG  = PWRGD_PVPP_ABC_R
  VIN(0)  = VR_FET_SW_P12V_STBY_PVPP_ABC
  VIN(1)  = VR_FET_SW_P12V_STBY_PVPP_ABC
  VIN(2)  = VR_FET_SW_P12V_STBY_PVPP_ABC
  VIN(3)  = VR_FET_SW_P12V_STBY_PVPP_ABC
  VIN(4)  = VR_FET_SW_P12V_STBY_PVPP_ABC
  VIN(5)  = VR_FET_SW_P12V_STBY_PVPP_ABC
  VIN(6)  = VR_FET_SW_P12V_STBY_PVPP_ABC
  VSWH(0)  = VR_PVPP_ABC_PHASE
  PGND(0)  = GND
  PGND(1)  = GND
  PGND(2)  = GND
  PGND(3)  = GND
  PGND(4)  = GND
  PGND(5)  = GND
  PGND(6)  = GND
  PGND(7)  = GND
  PGND(8)  = GND
  PGND(9)  = GND
  PGND(10)  = GND
  PGND(11)  = GND
  PGND(12)  = GND
  VSWH(1)  = VR_PVPP_ABC_PHASE
  VSWH(2)  = VR_PVPP_ABC_PHASE
  VSWH(3)  = VR_PVPP_ABC_PHASE
  VSWH(4)  = VR_PVPP_ABC_PHASE
  VSWH(5)  = VR_PVPP_ABC_PHASE
  VSWH(6)  = VR_PVPP_ABC_PHASE
  VSW  = VR_PVPP_ABC_PHASE
  BST  = VR_PVPP_ABC_BOOT
  PGND(13)  = GND
  VB  = VR_VB_PVPP_ABC
  VCC  = VR_FET_SW_P12V_STBY_PVPP_ABC
  EN  = FM_PVPP_PVDDQ_CPU0_EN_ABC
  GND  = GND
  VIN(7)  = VR_FET_SW_P12V_STBY_PVPP_ABC
  VSWH(7)  = VR_PVPP_ABC_PHASE

(kicad_pcb
	(version 20260206)
	(generator "pcbnew")
	(generator_version "10.0")
	(general
		(thickness 1.6)
		(legacy_teardrops no)
	)
	(paper "A4")
	(title_block
		(title "Wiwynn_Tioga_Pass_MB.brd")
		(comment 1 "Tioga Pass / footprint 636 of 4770 (EU7F1), pads 1-17 of 43")
	)
	(layers
		(0 "F.Cu" signal "TOP")
		(4 "In1.Cu" signal "L2GND")
		(6 "In2.Cu" signal "L3")
		(8 "In3.Cu" signal "L4GND")
		(10 "In4.Cu" signal "L5")
		(12 "In5.Cu" signal "L6GND")
		(14 "In6.Cu" signal "L7VCC")
		(16 "In7.Cu" signal "L8VCC")
		(18 "In8.Cu" signal "L9GND")
		(20 "In9.Cu" signal "L10")
		(22 "In10.Cu" signal "L11GND")
		(24 "In11.Cu" signal "L12")
		(26 "In12.Cu" signal "L13GND")
		(2 "B.Cu" signal "BOTTOM")
		(9 "F.Adhes" user "F.Adhesive")
		(11 "B.Adhes" user "B.Adhesive")
		(13 "F.Paste" user "Package Geometry/Pastemask Top")
		(15 "B.Paste" user "Package Geometry/Pastemask Bottom")
		(5 "F.SilkS" user "Ref Des/Silkscreen Top")
		(7 "B.SilkS" user "Ref Des/Silkscreen Bottom")
		(1 "F.Mask" user "Board Geometry/Soldermask Top")
		(3 "B.Mask" user "Board Geometry/Soldermask Bottom")
		(17 "Dwgs.User" user "User.Drawings")
		(19 "Cmts.User" user "User.Comments")
		(21 "Eco1.User" user "User.Eco1")
		(23 "Eco2.User" user "User.Eco2")
		(25 "Edge.Cuts" user "Board Geometry/Outline")
		(27 "Margin" user)
		(31 "F.CrtYd" user "Package Geometry/Place Bound Top")
		(29 "B.CrtYd" user "Package Geometry/Place Bound Bottom")
		(35 "F.Fab" user "Ref Des/Assembly Top")
		(33 "B.Fab" user "Ref Des/Assembly Bottom")
	)
	(footprint ""
		(layer "F.Cu")
		(at 345.3638 -28.5623 90)
		(property "Reference" "EU7F1"
			(at 5.27939 -1.76022 0)
			(unlocked yes)
			(layer "F.SilkS")
			(effects
				(font
					(size 0.7874 0.5842)
					(thickness 0.1524)
				)
				(justify left)
			)
		)
		(property "Value" ""
			(at 0 0 90)
			(layer "F.Fab")
			(effects
				(font
					(size 1.27 1.27)
				)
			)
		)
		(duplicate_pad_numbers_are_jumpers no)
		(pad "1" smd custom
			(at -2.8321 -2.249932 90)
			(size 0.06985 0.06985)
			(layers "F.Cu" "F.Mask" "F.Paste")
			(net "VR_PVPP_ABC_SS")
			(options
				(clearance outline)
				(anchor circle)
			)
			(primitives
				(gr_poly
					(pts
						(arc
							(start 0.2413 -0.1397)
							(mid 0.381 0)
							(end 0.2413 0.1397)
						)
						(xy -0.381 0.1397) (xy -0.381 -0.1397)
					)
					(width 0)
					(fill yes)
				)
			)
		)
		(pad "2" smd custom
			(at -2.8321 -1.75006 90)
			(size 0.06985 0.06985)
			(layers "F.Cu" "F.Mask" "F.Paste")
			(net "VR_FB_PVPP_ABC")
			(options
				(clearance outline)
				(anchor circle)
			)
			(primitives
				(gr_poly
					(pts
						(arc
							(start 0.2413 -0.1397)
							(mid 0.381 0)
							(end 0.2413 0.1397)
						)
						(xy -0.381 0.1397) (xy -0.381 -0.1397)
					)
					(width 0)
					(fill yes)
				)
			)
		)
		(pad "3" smd custom
			(at -2.8321 -1.249934 90)
			(size 0.06985 0.06985)
			(layers "F.Cu" "F.Mask" "F.Paste")
			(net "VR_COMP_PVPP_ABC_3")
			(options
				(clearance outline)
				(anchor circle)
			)
			(primitives
				(gr_poly
					(pts
						(arc
							(start 0.2413 -0.1397)
							(mid 0.381 0)
							(end 0.2413 0.1397)
						)
						(xy -0.381 0.1397) (xy -0.381 -0.1397)
					)
					(width 0)
					(fill yes)
				)
			)
		)
		(pad "4" smd custom
			(at -2.8321 -0.750062 90)
			(size 0.06985 0.06985)
			(layers "F.Cu" "F.Mask" "F.Paste")
			(net "VR_PVPP_ABC_ISET")
			(options
				(clearance outline)
				(anchor circle)
			)
			(primitives
				(gr_poly
					(pts
						(arc
							(start 0.2413 -0.1397)
							(mid 0.381 0)
							(end 0.2413 0.1397)
						)
						(xy -0.381 0.1397) (xy -0.381 -0.1397)
					)
					(width 0)
					(fill yes)
				)
			)
		)
		(pad "5" smd custom
			(at -2.8321 -0.249936 90)
			(size 0.06985 0.06985)
			(layers "F.Cu" "F.Mask" "F.Paste")
			(net "AGND_PVPP_ABC")
			(options
				(clearance outline)
				(anchor circle)
			)
			(primitives
				(gr_poly
					(pts
						(arc
							(start 0.2413 -0.1397)
							(mid 0.381 0)
							(end 0.2413 0.1397)
						)
						(xy -0.381 0.1397) (xy -0.381 -0.1397)
					)
					(width 0)
					(fill yes)
				)
			)
		)
		(pad "6" smd custom
			(at -2.8321 0.249936 90)
			(size 0.06985 0.06985)
			(layers "F.Cu" "F.Mask" "F.Paste")
			(net "AGND_PVPP_ABC")
			(options
				(clearance outline)
				(anchor circle)
			)
			(primitives
				(gr_poly
					(pts
						(arc
							(start 0.2413 -0.1397)
							(mid 0.381 0)
							(end 0.2413 0.1397)
						)
						(xy -0.381 0.1397) (xy -0.381 -0.1397)
					)
					(width 0)
					(fill yes)
				)
			)
		)
		(pad "7" smd custom
			(at -2.8321 0.750062 90)
			(size 0.06985 0.06985)
			(layers "F.Cu" "F.Mask" "F.Paste")
			(net "PWRGD_PVPP_ABC_R")
			(options
				(clearance outline)
				(anchor circle)
			)
			(primitives
				(gr_poly
					(pts
						(arc
							(start 0.2413 -0.1397)
							(mid 0.381 0)
							(end 0.2413 0.1397)
						)
						(xy -0.381 0.1397) (xy -0.381 -0.1397)
					)
					(width 0)
					(fill yes)
				)
			)
		)
		(pad "8" smd custom
			(at -2.8321 1.249934 90)
			(size 0.06985 0.06985)
			(layers "F.Cu" "F.Mask" "F.Paste")
			(net "VR_FET_SW_P12V_STBY_PVPP_ABC")
			(options
				(clearance outline)
				(anchor circle)
			)
			(primitives
				(gr_poly
					(pts
						(arc
							(start 0.2413 -0.1397)
							(mid 0.381 0)
							(end 0.2413 0.1397)
						)
						(xy -0.381 0.1397) (xy -0.381 -0.1397)
					)
					(width 0)
					(fill yes)
				)
			)
		)
		(pad "9" smd custom
			(at -2.8321 1.75006 90)
			(size 0.06985 0.06985)
			(layers "F.Cu" "F.Mask" "F.Paste")
			(net "VR_FET_SW_P12V_STBY_PVPP_ABC")
			(options
				(clearance outline)
				(anchor circle)
			)
			(primitives
				(gr_poly
					(pts
						(arc
							(start 0.2413 -0.1397)
							(mid 0.381 0)
							(end 0.2413 0.1397)
						)
						(xy -0.381 0.1397) (xy -0.381 -0.1397)
					)
					(width 0)
					(fill yes)
				)
			)
		)
		(pad "10" smd custom
			(at -2.8321 2.249932 90)
			(size 0.06985 0.06985)
			(layers "F.Cu" "F.Mask" "F.Paste")
			(net "VR_FET_SW_P12V_STBY_PVPP_ABC")
			(options
				(clearance outline)
				(anchor circle)
			)
			(primitives
				(gr_poly
					(pts
						(arc
							(start 0.2413 -0.1397)
							(mid 0.381 0)
							(end 0.2413 0.1397)
						)
						(xy -0.381 0.1397) (xy -0.381 -0.1397)
					)
					(width 0)
					(fill yes)
				)
			)
		)
		(pad "11" smd custom
			(at -2.249932 2.8321 90)
			(size 0.06985 0.06985)
			(layers "F.Cu" "F.Mask" "F.Paste")
			(net "VR_FET_SW_P12V_STBY_PVPP_ABC")
			(options
				(clearance outline)
				(anchor circle)
			)
			(primitives
				(gr_poly
					(pts
						(arc
							(start -0.1397 -0.2413)
							(mid 0 -0.381)
							(end 0.1397 -0.2413)
						)
						(xy 0.1397 0.381) (xy -0.1397 0.381)
					)
					(width 0)
					(fill yes)
				)
			)
		)
		(pad "12" smd custom
			(at -1.75006 2.8321 90)
			(size 0.06985 0.06985)
			(layers "F.Cu" "F.Mask" "F.Paste")
			(net "VR_FET_SW_P12V_STBY_PVPP_ABC")
			(options
				(clearance outline)
				(anchor circle)
			)
			(primitives
				(gr_poly
					(pts
						(arc
							(start -0.1397 -0.2413)
							(mid 0 -0.381)
							(end 0.1397 -0.2413)
						)
						(xy 0.1397 0.381) (xy -0.1397 0.381)
					)
					(width 0)
					(fill yes)
				)
			)
		)
		(pad "13" smd custom
			(at -1.249934 2.8321 90)
			(size 0.06985 0.06985)
			(layers "F.Cu" "F.Mask" "F.Paste")
			(net "VR_FET_SW_P12V_STBY_PVPP_ABC")
			(options
				(clearance outline)
				(anchor circle)
			)
			(primitives
				(gr_poly
					(pts
						(arc
							(start -0.1397 -0.2413)
							(mid 0 -0.381)
							(end 0.1397 -0.2413)
						)
						(xy 0.1397 0.381) (xy -0.1397 0.381)
					)
					(width 0)
					(fill yes)
				)
			)
		)
		(pad "14" smd custom
			(at -0.750062 2.8321 90)
			(size 0.06985 0.06985)
			(layers "F.Cu" "F.Mask" "F.Paste")
			(net "VR_FET_SW_P12V_STBY_PVPP_ABC")
			(options
				(clearance outline)
				(anchor circle)
			)
			(primitives
				(gr_poly
					(pts
						(arc
							(start -0.1397 -0.2413)
							(mid 0 -0.381)
							(end 0.1397 -0.2413)
						)
						(xy 0.1397 0.381) (xy -0.1397 0.381)
					)
					(width 0)
					(fill yes)
				)
			)
		)
		(pad "15" smd custom
			(at -0.249936 2.8321 90)
			(size 0.06985 0.06985)
			(layers "F.Cu" "F.Mask" "F.Paste")
			(net "VR_PVPP_ABC_PHASE")
			(options
				(clearance outline)
				(anchor circle)
			)
			(primitives
				(gr_poly
					(pts
						(arc
							(start -0.1397 -0.2413)
							(mid 0 -0.381)
							(end 0.1397 -0.2413)
						)
						(xy 0.1397 0.381) (xy -0.1397 0.381)
					)
					(width 0)
					(fill yes)
				)
			)
		)
		(pad "16" smd custom
			(at 0.249936 2.8321 90)
			(size 0.06985 0.06985)
			(layers "F.Cu" "F.Mask" "F.Paste")
			(net "GND")
			(options
				(clearance outline)
				(anchor circle)
			)
			(primitives
				(gr_poly
					(pts
						(arc
							(start -0.1397 -0.2413)
							(mid 0 -0.381)
							(end 0.1397 -0.2413)
						)
						(xy 0.1397 0.381) (xy -0.1397 0.381)
					)
					(width 0)
					(fill yes)
				)
			)
		)
		(pad "17" smd custom
			(at 0.750062 2.8321 90)
			(size 0.06985 0.06985)
			(layers "F.Cu" "F.Mask" "F.Paste")
			(net "GND")
			(options
				(clearance outline)
				(anchor circle)
			)
			(primitives
				(gr_poly
					(pts
						(arc
							(start -0.1397 -0.2413)
							(mid 0 -0.381)
							(end 0.1397 -0.2413)
						)
						(xy 0.1397 0.381) (xy -0.1397 0.381)
					)
					(width 0)
					(fill yes)
				)
			)
		)
	)
)
